(kicad_pcb
	(version 20260206)
	(generator "pcbnew")
	(generator_version "10.0")
	(general
		(thickness 1.6)
		(legacy_teardrops no)
	)
	(paper "A4")
	(title_block
		(title "Bryce Canyon_LED_16347-1_OCP.brd")
		(comment 1 "Bryce Canyon / footprints 31-36 of 49")
	)
	(layers
		(0 "F.Cu" signal "TOP")
		(2 "B.Cu" signal "BOTTOM")
		(9 "F.Adhes" user "F.Adhesive")
		(11 "B.Adhes" user "B.Adhesive")
		(13 "F.Paste" user "Package Geometry/Pastemask Top")
		(15 "B.Paste" user "Package Geometry/Pastemask Bottom")
		(5 "F.SilkS" user "Ref Des/Silkscreen Top")
		(7 "B.SilkS" user "Ref Des/Silkscreen Bottom")
		(1 "F.Mask" user "Board Geometry/Soldermask Top")
		(3 "B.Mask" user "Board Geometry/Soldermask Bottom")
		(17 "Dwgs.User" user "User.Drawings")
		(19 "Cmts.User" user "User.Comments")
		(21 "Eco1.User" user "User.Eco1")
		(23 "Eco2.User" user "User.Eco2")
		(25 "Edge.Cuts" user "Board Geometry/Outline")
		(27 "Margin" user)
		(31 "F.CrtYd" user "Package Geometry/Place Bound Top")
		(29 "B.CrtYd" user "Package Geometry/Place Bound Bottom")
		(35 "F.Fab" user "Ref Des/Assembly Top")
		(33 "B.Fab" user "Ref Des/Assembly Bottom")
	)
	(footprint ""
		(layer "B.Cu")
		(at 103.9876 -6.0198 180)
		(property "Reference" "R7"
			(at 0 0 0)
			(layer "B.SilkS")
			(hide yes)
			(effects
				(font
					(size 1.27 1.27)
				)
				(justify mirror)
			)
		)
		(property "Value" "130R3F-GP"
			(at 0.0254 -2.5146 180)
			(unlocked yes)
			(layer "B.Fab")
			(hide yes)
			(effects
				(font
					(size 1.016 1.016)
					(thickness 0.1524)
				)
				(justify mirror)
			)
		)
		(property "Device Type" "R603H22"
			(at 0.0254 -4.0386 180)
			(unlocked yes)
			(layer "B.Fab")
			(hide yes)
			(effects
				(font
					(size 1.016 1.016)
					(thickness 0.1524)
				)
				(justify mirror)
			)
		)
		(duplicate_pad_numbers_are_jumpers no)
		(fp_line
			(start 0.4826 0)
			(end 0.2032 0)
			(stroke
				(width 0.2032)
				(type default)
			)
			(layer "B.SilkS")
		)
		(fp_line
			(start -0.2032 0)
			(end -0.4826 0)
			(stroke
				(width 0.2032)
				(type default)
			)
			(layer "B.SilkS")
		)
		(fp_rect
			(start 0.5842 1.3335)
			(end -0.5842 -1.3335)
			(stroke
				(width 0)
				(type default)
			)
			(fill no)
			(layer "B.CrtYd")
		)
		(fp_rect
			(start 0.5842 1.3335)
			(end -0.5842 -1.3335)
			(stroke
				(width 0)
				(type default)
			)
			(fill no)
			(layer "B.Fab")
		)
		(pad "1" smd custom
			(at 0 -0.762)
			(size 0.2159 0.2159)
			(layers "B.Cu" "B.Mask" "B.Paste")
			(net "P5V_A")
			(options
				(clearance outline)
				(anchor circle)
			)
			(primitives
				(gr_poly
					(pts
						(arc
							(start -0.3302 0.4318)
							(mid -0.402042 0.402042)
							(end -0.4318 0.3302)
						)
						(arc
							(start -0.4318 -0.3302)
							(mid -0.402042 -0.402042)
							(end -0.3302 -0.4318)
						)
						(arc
							(start 0.3302 -0.4318)
							(mid 0.402042 -0.402042)
							(end 0.4318 -0.3302)
						)
						(arc
							(start 0.4318 0.3302)
							(mid 0.402042 0.402042)
							(end 0.3302 0.4318)
						)
					)
					(width 0)
					(fill yes)
				)
			)
		)
		(pad "2" smd custom
			(at 0 0.762)
			(size 0.2159 0.2159)
			(layers "B.Cu" "B.Mask" "B.Paste")
			(net "FLT_HDD27_33")
			(options
				(clearance outline)
				(anchor circle)
			)
			(primitives
				(gr_poly
					(pts
						(arc
							(start -0.3302 0.4318)
							(mid -0.402042 0.402042)
							(end -0.4318 0.3302)
						)
						(arc
							(start -0.4318 -0.3302)
							(mid -0.402042 -0.402042)
							(end -0.3302 -0.4318)
						)
						(arc
							(start 0.3302 -0.4318)
							(mid 0.402042 -0.402042)
							(end 0.4318 -0.3302)
						)
						(arc
							(start 0.4318 0.3302)
							(mid 0.402042 0.402042)
							(end 0.3302 0.4318)
						)
					)
					(width 0)
					(fill yes)
				)
			)
		)
	)
	(footprint ""
		(layer "B.Cu")
		(at 24.6888 -5.9436 180)
		(property "Reference" "R2"
			(at 0 0 0)
			(layer "B.SilkS")
			(hide yes)
			(effects
				(font
					(size 1.27 1.27)
				)
				(justify mirror)
			)
		)
		(property "Value" "91R3F-1-GP"
			(at 0.0254 -2.5146 180)
			(unlocked yes)
			(layer "B.Fab")
			(hide yes)
			(effects
				(font
					(size 1.016 1.016)
					(thickness 0.1524)
				)
				(justify mirror)
			)
		)
		(property "Device Type" "R603H22"
			(at 0.0254 -4.0386 180)
			(unlocked yes)
			(layer "B.Fab")
			(hide yes)
			(effects
				(font
					(size 1.016 1.016)
					(thickness 0.1524)
				)
				(justify mirror)
			)
		)
		(duplicate_pad_numbers_are_jumpers no)
		(fp_line
			(start 0.4826 0)
			(end 0.2032 0)
			(stroke
				(width 0.2032)
				(type default)
			)
			(layer "B.SilkS")
		)
		(fp_line
			(start -0.2032 0)
			(end -0.4826 0)
			(stroke
				(width 0.2032)
				(type default)
			)
			(layer "B.SilkS")
		)
		(fp_rect
			(start 0.5842 1.3335)
			(end -0.5842 -1.3335)
			(stroke
				(width 0)
				(type default)
			)
			(fill no)
			(layer "B.CrtYd")
		)
		(fp_rect
			(start 0.5842 1.3335)
			(end -0.5842 -1.3335)
			(stroke
				(width 0)
				(type default)
			)
			(fill no)
			(layer "B.Fab")
		)
		(pad "1" smd custom
			(at 0 -0.762)
			(size 0.2159 0.2159)
			(layers "B.Cu" "B.Mask" "B.Paste")
			(net "P5V_A")
			(options
				(clearance outline)
				(anchor circle)
			)
			(primitives
				(gr_poly
					(pts
						(arc
							(start -0.3302 0.4318)
							(mid -0.402042 0.402042)
							(end -0.4318 0.3302)
						)
						(arc
							(start -0.4318 -0.3302)
							(mid -0.402042 -0.402042)
							(end -0.3302 -0.4318)
						)
						(arc
							(start 0.3302 -0.4318)
							(mid 0.402042 -0.402042)
							(end 0.4318 -0.3302)
						)
						(arc
							(start 0.4318 0.3302)
							(mid 0.402042 0.402042)
							(end 0.3302 0.4318)
						)
					)
					(width 0)
					(fill yes)
				)
			)
		)
		(pad "2" smd custom
			(at 0 0.762)
			(size 0.2159 0.2159)
			(layers "B.Cu" "B.Mask" "B.Paste")
			(net "DRV_ACT_24_30")
			(options
				(clearance outline)
				(anchor circle)
			)
			(primitives
				(gr_poly
					(pts
						(arc
							(start -0.3302 0.4318)
							(mid -0.402042 0.402042)
							(end -0.4318 0.3302)
						)
						(arc
							(start -0.4318 -0.3302)
							(mid -0.402042 -0.402042)
							(end -0.3302 -0.4318)
						)
						(arc
							(start 0.3302 -0.4318)
							(mid 0.402042 -0.402042)
							(end 0.4318 -0.3302)
						)
						(arc
							(start 0.4318 0.3302)
							(mid 0.402042 0.402042)
							(end 0.3302 0.4318)
						)
					)
					(width 0)
					(fill yes)
				)
			)
		)
	)
	(footprint ""
		(layer "B.Cu")
		(at 161.925 -5.588)
		(property "Reference" "Q11"
			(at 0 0 0)
			(layer "B.SilkS")
			(hide yes)
			(effects
				(font
					(size 1.27 1.27)
				)
				(justify mirror)
			)
		)
		(property "Value" "2N7002K-2-GP"
			(at -0.127 -8.9662 0)
			(unlocked yes)
			(layer "B.Fab")
			(hide yes)
			(effects
				(font
					(size 1.016 1.016)
					(thickness 0.1524)
				)
				(justify mirror)
			)
		)
		(property "Device Type" "SOT23DGS2D4H44"
			(at -0.127 -10.4902 0)
			(unlocked yes)
			(layer "B.Fab")
			(hide yes)
			(effects
				(font
					(size 1.016 1.016)
					(thickness 0.1524)
				)
				(justify mirror)
			)
		)
		(duplicate_pad_numbers_are_jumpers no)
		(fp_line
			(start -1.651 -1.778)
			(end 1.651 -1.778)
			(stroke
				(width 0.1524)
				(type default)
			)
			(layer "B.SilkS")
		)
		(fp_line
			(start -1.651 1.778)
			(end -1.651 -1.778)
			(stroke
				(width 0.1524)
				(type default)
			)
			(layer "B.SilkS")
		)
		(fp_line
			(start 1.651 -1.778)
			(end 1.651 1.778)
			(stroke
				(width 0.1524)
				(type default)
			)
			(layer "B.SilkS")
		)
		(fp_line
			(start 1.651 1.778)
			(end -1.651 1.778)
			(stroke
				(width 0.1524)
				(type default)
			)
			(layer "B.SilkS")
		)
		(fp_poly
			(pts
				(xy 1.778 1.8796) (xy 1.778 -1.8796) (xy -1.778 -1.8796) (xy -1.778 1.8796)
			)
			(stroke
				(width 0)
				(type default)
			)
			(fill no)
			(layer "B.CrtYd")
		)
		(fp_poly
			(pts
				(xy 1.778 1.8796) (xy 1.778 -1.8796) (xy -1.778 -1.8796) (xy -1.778 1.8796)
			)
			(stroke
				(width 0)
				(type default)
			)
			(fill no)
			(layer "B.Fab")
		)
		(pad "D" smd custom
			(at 0 -0.9525 180)
			(size 0.1905 0.1905)
			(layers "B.Cu" "B.Mask" "B.Paste")
			(net "FLT_HDD29_35_N")
			(options
				(clearance outline)
				(anchor circle)
			)
			(primitives
				(gr_poly
					(pts
						(arc
							(start -0.1778 -0.5715)
							(mid -0.321484 -0.511984)
							(end -0.381 -0.3683)
						)
						(arc
							(start -0.381 0.3683)
							(mid -0.321484 0.511984)
							(end -0.1778 0.5715)
						)
						(arc
							(start 0.1778 0.5715)
							(mid 0.321484 0.511984)
							(end 0.381 0.3683)
						)
						(arc
							(start 0.381 -0.3683)
							(mid 0.321484 -0.511984)
							(end 0.1778 -0.5715)
						)
					)
					(width 0)
					(fill yes)
				)
			)
		)
		(pad "G" smd custom
			(at 0.98425 0.9525 180)
			(size 0.1905 0.1905)
			(layers "B.Cu" "B.Mask" "B.Paste")
			(net "DRIVE_A_29_35_FLT_LED")
			(options
				(clearance outline)
				(anchor circle)
			)
			(primitives
				(gr_poly
					(pts
						(arc
							(start -0.1778 -0.5715)
							(mid -0.321484 -0.511984)
							(end -0.381 -0.3683)
						)
						(arc
							(start -0.381 0.3683)
							(mid -0.321484 0.511984)
							(end -0.1778 0.5715)
						)
						(arc
							(start 0.1778 0.5715)
							(mid 0.321484 0.511984)
							(end 0.381 0.3683)
						)
						(arc
							(start 0.381 -0.3683)
							(mid 0.321484 -0.511984)
							(end 0.1778 -0.5715)
						)
					)
					(width 0)
					(fill yes)
				)
			)
		)
		(pad "S" smd custom
			(at -0.98425 0.9525 180)
			(size 0.1905 0.1905)
			(layers "B.Cu" "B.Mask" "B.Paste")
			(net "GND")
			(options
				(clearance outline)
				(anchor circle)
			)
			(primitives
				(gr_poly
					(pts
						(arc
							(start -0.1778 -0.5715)
							(mid -0.321484 -0.511984)
							(end -0.381 -0.3683)
						)
						(arc
							(start -0.381 0.3683)
							(mid -0.321484 0.511984)
							(end -0.1778 0.5715)
						)
						(arc
							(start 0.1778 0.5715)
							(mid 0.321484 0.511984)
							(end 0.381 0.3683)
						)
						(arc
							(start 0.381 -0.3683)
							(mid 0.321484 -0.511984)
							(end 0.1778 -0.5715)
						)
					)
					(width 0)
					(fill yes)
				)
			)
		)
	)
	(footprint ""
		(layer "B.Cu")
		(at 62.421262 -6.201918 180)
		(property "Reference" "R5"
			(at 0 0 0)
			(layer "B.SilkS")
			(hide yes)
			(effects
				(font
					(size 1.27 1.27)
				)
				(justify mirror)
			)
		)
		(property "Value" "130R3F-GP"
			(at 0.0254 -2.5146 180)
			(unlocked yes)
			(layer "B.Fab")
			(hide yes)
			(effects
				(font
					(size 1.016 1.016)
					(thickness 0.1524)
				)
				(justify mirror)
			)
		)
		(property "Device Type" "R603H22"
			(at 0.0254 -4.0386 180)
			(unlocked yes)
			(layer "B.Fab")
			(hide yes)
			(effects
				(font
					(size 1.016 1.016)
					(thickness 0.1524)
				)
				(justify mirror)
			)
		)
		(duplicate_pad_numbers_are_jumpers no)
		(fp_line
			(start 0.4826 0)
			(end 0.2032 0)
			(stroke
				(width 0.2032)
				(type default)
			)
			(layer "B.SilkS")
		)
		(fp_line
			(start -0.2032 0)
			(end -0.4826 0)
			(stroke
				(width 0.2032)
				(type default)
			)
			(layer "B.SilkS")
		)
		(fp_rect
			(start 0.5842 1.3335)
			(end -0.5842 -1.3335)
			(stroke
				(width 0)
				(type default)
			)
			(fill no)
			(layer "B.CrtYd")
		)
		(fp_rect
			(start 0.5842 1.3335)
			(end -0.5842 -1.3335)
			(stroke
				(width 0)
				(type default)
			)
			(fill no)
			(layer "B.Fab")
		)
		(pad "1" smd custom
			(at 0 -0.762)
			(size 0.2159 0.2159)
			(layers "B.Cu" "B.Mask" "B.Paste")
			(net "P5V_A")
			(options
				(clearance outline)
				(anchor circle)
			)
			(primitives
				(gr_poly
					(pts
						(arc
							(start -0.3302 0.4318)
							(mid -0.402042 0.402042)
							(end -0.4318 0.3302)
						)
						(arc
							(start -0.4318 -0.3302)
							(mid -0.402042 -0.402042)
							(end -0.3302 -0.4318)
						)
						(arc
							(start 0.3302 -0.4318)
							(mid 0.402042 -0.402042)
							(end 0.4318 -0.3302)
						)
						(arc
							(start 0.4318 0.3302)
							(mid 0.402042 0.402042)
							(end 0.3302 0.4318)
						)
					)
					(width 0)
					(fill yes)
				)
			)
		)
		(pad "2" smd custom
			(at 0 0.762)
			(size 0.2159 0.2159)
			(layers "B.Cu" "B.Mask" "B.Paste")
			(net "FLT_HDD26_32")
			(options
				(clearance outline)
				(anchor circle)
			)
			(primitives
				(gr_poly
					(pts
						(arc
							(start -0.3302 0.4318)
							(mid -0.402042 0.402042)
							(end -0.4318 0.3302)
						)
						(arc
							(start -0.4318 -0.3302)
							(mid -0.402042 -0.402042)
							(end -0.3302 -0.4318)
						)
						(arc
							(start 0.3302 -0.4318)
							(mid 0.402042 -0.402042)
							(end 0.4318 -0.3302)
						)
						(arc
							(start 0.4318 0.3302)
							(mid 0.402042 0.402042)
							(end 0.3302 0.4318)
						)
					)
					(width 0)
					(fill yes)
				)
			)
		)
	)
	(footprint ""
		(layer "B.Cu")
		(at 106.6292 -3.5052 -90)
		(property "Reference" "R19"
			(at 0 0 90)
			(layer "B.SilkS")
			(hide yes)
			(effects
				(font
					(size 1.27 1.27)
				)
				(justify mirror)
			)
		)
		(property "Value" "4K7R2F-GP"
			(at -0.064008 -3.993896 270)
			(unlocked yes)
			(layer "B.Fab")
			(hide yes)
			(effects
				(font
					(size 1.016 1.016)
					(thickness 0.1524)
				)
				(justify mirror)
			)
		)
		(property "Device Type" "R402H16"
			(at -0.064008 -5.517896 270)
			(unlocked yes)
			(layer "B.Fab")
			(hide yes)
			(effects
				(font
					(size 1.016 1.016)
					(thickness 0.1524)
				)
				(justify mirror)
			)
		)
		(duplicate_pad_numbers_are_jumpers no)
		(fp_line
			(start -0.508 -0.9398)
			(end 0.508 -0.9398)
			(stroke
				(width 0.1524)
				(type default)
			)
			(layer "B.SilkS")
		)
		(fp_line
			(start 0.508 -0.9398)
			(end 0.508 0.9398)
			(stroke
				(width 0.1524)
				(type default)
			)
			(layer "B.SilkS")
		)
		(fp_rect
			(start 0.508 0.9398)
			(end -0.508 -0.9398)
			(stroke
				(width 0)
				(type default)
			)
			(fill no)
			(layer "B.CrtYd")
		)
		(fp_rect
			(start 0.508 0.9398)
			(end -0.508 -0.9398)
			(stroke
				(width 0)
				(type default)
			)
			(fill no)
			(layer "B.Fab")
		)
		(pad "1" smd custom
			(at 0 -0.4445 90)
			(size 0.1397 0.1397)
			(layers "B.Cu" "B.Mask" "B.Paste")
			(net "DRIVE_A_27_33_FLT_LED")
			(options
				(clearance outline)
				(anchor circle)
			)
			(primitives
				(gr_poly
					(pts
						(arc
							(start -0.1778 0.2794)
							(mid -0.249642 0.249642)
							(end -0.2794 0.1778)
						)
						(arc
							(start -0.2794 -0.1778)
							(mid -0.249642 -0.249642)
							(end -0.1778 -0.2794)
						)
						(arc
							(start 0.1778 -0.2794)
							(mid 0.249642 -0.249642)
							(end 0.2794 -0.1778)
						)
						(arc
							(start 0.2794 0.1778)
							(mid 0.249642 0.249642)
							(end 0.1778 0.2794)
						)
					)
					(width 0)
					(fill yes)
				)
			)
		)
		(pad "2" smd custom
			(at 0 0.4445 90)
			(size 0.1397 0.1397)
			(layers "B.Cu" "B.Mask" "B.Paste")
			(net "GND")
			(options
				(clearance outline)
				(anchor circle)
			)
			(primitives
				(gr_poly
					(pts
						(arc
							(start -0.1778 0.2794)
							(mid -0.249642 0.249642)
							(end -0.2794 0.1778)
						)
						(arc
							(start -0.2794 -0.1778)
							(mid -0.249642 -0.249642)
							(end -0.1778 -0.2794)
						)
						(arc
							(start 0.1778 -0.2794)
							(mid 0.249642 -0.249642)
							(end 0.2794 -0.1778)
						)
						(arc
							(start 0.2794 0.1778)
							(mid 0.249642 0.249642)
							(end 0.1778 0.2794)
						)
					)
					(width 0)
					(fill yes)
				)
			)
		)
	)
	(footprint ""
		(layer "B.Cu")
		(at 28.448 -5.0546)
		(property "Reference" "Q3"
			(at 0 0 0)
			(layer "B.SilkS")
			(hide yes)
			(effects
				(font
					(size 1.27 1.27)
				)
				(justify mirror)
			)
		)
		(property "Value" "2N7002K-2-GP"
			(at -0.127 -8.9662 0)
			(unlocked yes)
			(layer "B.Fab")
			(hide yes)
			(effects
				(font
					(size 1.016 1.016)
					(thickness 0.1524)
				)
				(justify mirror)
			)
		)
		(property "Device Type" "SOT23DGS2D4H44"
			(at -0.127 -10.4902 0)
			(unlocked yes)
			(layer "B.Fab")
			(hide yes)
			(effects
				(font
					(size 1.016 1.016)
					(thickness 0.1524)
				)
				(justify mirror)
			)
		)
		(duplicate_pad_numbers_are_jumpers no)
		(fp_line
			(start -1.651 -1.778)
			(end 1.651 -1.778)
			(stroke
				(width 0.1524)
				(type default)
			)
			(layer "B.SilkS")
		)
		(fp_line
			(start -1.651 1.778)
			(end -1.651 -1.778)
			(stroke
				(width 0.1524)
				(type default)
			)
			(layer "B.SilkS")
		)
		(fp_line
			(start 1.651 -1.778)
			(end 1.651 1.778)
			(stroke
				(width 0.1524)
				(type default)
			)
			(layer "B.SilkS")
		)
		(fp_line
			(start 1.651 1.778)
			(end -1.651 1.778)
			(stroke
				(width 0.1524)
				(type default)
			)
			(layer "B.SilkS")
		)
		(fp_poly
			(pts
				(xy 1.778 1.8796) (xy 1.778 -1.8796) (xy -1.778 -1.8796) (xy -1.778 1.8796)
			)
			(stroke
				(width 0)
				(type default)
			)
			(fill no)
			(layer "B.CrtYd")
		)
		(fp_poly
			(pts
				(xy 1.778 1.8796) (xy 1.778 -1.8796) (xy -1.778 -1.8796) (xy -1.778 1.8796)
			)
			(stroke
				(width 0)
				(type default)
			)
			(fill no)
			(layer "B.Fab")
		)
		(pad "D" smd custom
			(at 0 -0.9525 180)
			(size 0.1905 0.1905)
			(layers "B.Cu" "B.Mask" "B.Paste")
			(net "FLT_HDD25_31_N")
			(options
				(clearance outline)
				(anchor circle)
			)
			(primitives
				(gr_poly
					(pts
						(arc
							(start -0.1778 -0.5715)
							(mid -0.321484 -0.511984)
							(end -0.381 -0.3683)
						)
						(arc
							(start -0.381 0.3683)
							(mid -0.321484 0.511984)
							(end -0.1778 0.5715)
						)
						(arc
							(start 0.1778 0.5715)
							(mid 0.321484 0.511984)
							(end 0.381 0.3683)
						)
						(arc
							(start 0.381 -0.3683)
							(mid 0.321484 -0.511984)
							(end 0.1778 -0.5715)
						)
					)
					(width 0)
					(fill yes)
				)
			)
		)
		(pad "G" smd custom
			(at 0.98425 0.9525 180)
			(size 0.1905 0.1905)
			(layers "B.Cu" "B.Mask" "B.Paste")
			(net "DRIVE_A_25_31_FLT_LED")
			(options
				(clearance outline)
				(anchor circle)
			)
			(primitives
				(gr_poly
					(pts
						(arc
							(start -0.1778 -0.5715)
							(mid -0.321484 -0.511984)
							(end -0.381 -0.3683)
						)
						(arc
							(start -0.381 0.3683)
							(mid -0.321484 0.511984)
							(end -0.1778 0.5715)
						)
						(arc
							(start 0.1778 0.5715)
							(mid 0.321484 0.511984)
							(end 0.381 0.3683)
						)
						(arc
							(start 0.381 -0.3683)
							(mid 0.321484 -0.511984)
							(end 0.1778 -0.5715)
						)
					)
					(width 0)
					(fill yes)
				)
			)
		)
		(pad "S" smd custom
			(at -0.98425 0.9525 180)
			(size 0.1905 0.1905)
			(layers "B.Cu" "B.Mask" "B.Paste")
			(net "GND")
			(options
				(clearance outline)
				(anchor circle)
			)
			(primitives
				(gr_poly
					(pts
						(arc
							(start -0.1778 -0.5715)
							(mid -0.321484 -0.511984)
							(end -0.381 -0.3683)
						)
						(arc
							(start -0.381 0.3683)
							(mid -0.321484 0.511984)
							(end -0.1778 0.5715)
						)
						(arc
							(start 0.1778 0.5715)
							(mid 0.321484 0.511984)
							(end 0.381 0.3683)
						)
						(arc
							(start 0.381 -0.3683)
							(mid 0.321484 -0.511984)
							(end 0.1778 -0.5715)
						)
					)
					(width 0)
					(fill yes)
				)
			)
		)
	)
)
